# BASEBOARD_FAB2 (Tioga Pass) — schematic netlist excerpt (pin names and nets, part order shuffled) for the footprints in the layout excerpt that follows; sources: Cadence DE-HDL packaged netlist, KiCad conversion of Wiwynn_Tioga_Pass_MB.brd

C1C23  CAP  1000PF 50V 10% X7R  pkg 0402LF  page 206 : A = VR_VRRDY_PVCCIN_CPU1 ; B = GND
R4A6  RES  33.2 1% CHIP  pkg 0402  page 222 : A = PWRGD_PVTT_DEF_CPU0_R ; B = PWRGD_PVTT_CPU0

(kicad_pcb
	(version 20260206)
	(generator "pcbnew")
	(generator_version "10.0")
	(general
		(thickness 1.6)
		(legacy_teardrops no)
	)
	(paper "A4")
	(title_block
		(title "Wiwynn_Tioga_Pass_MB.brd")
		(comment 1 "Tioga Pass / footprints 684-685 of 4770")
	)
	(layers
		(0 "F.Cu" signal "TOP")
		(4 "In1.Cu" signal "L2GND")
		(6 "In2.Cu" signal "L3")
		(8 "In3.Cu" signal "L4GND")
		(10 "In4.Cu" signal "L5")
		(12 "In5.Cu" signal "L6GND")
		(14 "In6.Cu" signal "L7VCC")
		(16 "In7.Cu" signal "L8VCC")
		(18 "In8.Cu" signal "L9GND")
		(20 "In9.Cu" signal "L10")
		(22 "In10.Cu" signal "L11GND")
		(24 "In11.Cu" signal "L12")
		(26 "In12.Cu" signal "L13GND")
		(2 "B.Cu" signal "BOTTOM")
		(9 "F.Adhes" user "F.Adhesive")
		(11 "B.Adhes" user "B.Adhesive")
		(13 "F.Paste" user "Package Geometry/Pastemask Top")
		(15 "B.Paste" user "Package Geometry/Pastemask Bottom")
		(5 "F.SilkS" user "Ref Des/Silkscreen Top")
		(7 "B.SilkS" user "Ref Des/Silkscreen Bottom")
		(1 "F.Mask" user "Board Geometry/Soldermask Top")
		(3 "B.Mask" user "Board Geometry/Soldermask Bottom")
		(17 "Dwgs.User" user "User.Drawings")
		(19 "Cmts.User" user "User.Comments")
		(21 "Eco1.User" user "User.Eco1")
		(23 "Eco2.User" user "User.Eco2")
		(25 "Edge.Cuts" user "Board Geometry/Outline")
		(27 "Margin" user)
		(31 "F.CrtYd" user "Package Geometry/Place Bound Top")
		(29 "B.CrtYd" user "Package Geometry/Place Bound Bottom")
		(35 "F.Fab" user "Ref Des/Assembly Top")
		(33 "B.Fab" user "Ref Des/Assembly Bottom")
	)
	(footprint ""
		(layer "F.Cu")
		(at 14.732 -90.0684 -90)
		(property "Reference" "C1C23"
			(at 0 0 270)
			(layer "F.SilkS")
			(hide yes)
			(effects
				(font
					(size 1.27 1.27)
				)
			)
		)
		(property "Value" ""
			(at 0 0 270)
			(layer "F.Fab")
			(effects
				(font
					(size 1.27 1.27)
				)
			)
		)
		(duplicate_pad_numbers_are_jumpers no)
		(fp_rect
			(start 0.3048 0.9906)
			(end -0.3048 -0.1016)
			(stroke
				(width 0)
				(type default)
			)
			(fill no)
			(layer "F.CrtYd")
		)
		(fp_line
			(start -0.3048 0.9906)
			(end 0.3048 0.9906)
			(stroke
				(width 0.1)
				(type default)
			)
			(layer "F.Fab")
		)
		(fp_line
			(start 0.3048 0.9906)
			(end 0.3048 -0.1016)
			(stroke
				(width 0.1)
				(type default)
			)
			(layer "F.Fab")
		)
		(fp_line
			(start -0.3048 -0.1016)
			(end -0.3048 0.9906)
			(stroke
				(width 0.1)
				(type default)
			)
			(layer "F.Fab")
		)
		(fp_line
			(start 0.3048 -0.1016)
			(end -0.3048 -0.1016)
			(stroke
				(width 0.1)
				(type default)
			)
			(layer "F.Fab")
		)
		(pad "1" smd rect
			(at 0 0 270)
			(size 0.508 0.508)
			(layers "F.Cu" "F.Mask" "F.Paste")
			(net "VR_VRRDY_PVCCIN_CPU1")
		)
		(pad "2" smd rect
			(at 0 0.889 270)
			(size 0.508 0.508)
			(layers "F.Cu" "F.Mask" "F.Paste")
			(net "GND")
		)
		(zone
			(layer "F.Cu")
			(hatch none 0.5)
			(connect_pads
				(clearance 0)
			)
			(min_thickness 0.25)
			(keepout
				(tracks not_allowed)
				(vias allowed)
				(pads allowed)
				(copperpour not_allowed)
				(footprints allowed)
			)
			(placement
				(enabled no)
				(sheetname "")
			)
			(fill
				(thermal_gap 0.5)
				(thermal_bridge_width 0.5)
				(island_removal_mode 0)
			)
			(polygon
				(pts
					(xy 14.097 -89.8144) (xy 14.478 -89.8144) (xy 14.478 -90.3224) (xy 14.097 -90.3224)
				)
			)
		)
		(zone
			(layer "F.Cu")
			(hatch none 0.5)
			(connect_pads
				(clearance 0)
			)
			(min_thickness 0.25)
			(keepout
				(tracks allowed)
				(vias not_allowed)
				(pads allowed)
				(copperpour not_allowed)
				(footprints allowed)
			)
			(placement
				(enabled no)
				(sheetname "")
			)
			(fill
				(thermal_gap 0.5)
				(thermal_bridge_width 0.5)
				(island_removal_mode 0)
			)
			(polygon
				(pts
					(xy 14.097 -89.8144) (xy 14.478 -89.8144) (xy 14.478 -90.3224) (xy 14.097 -90.3224)
				)
			)
		)
	)
	(footprint ""
		(layer "F.Cu")
		(at 185.4454 -146.6723)
		(property "Reference" "R4A6"
			(at 0 0 0)
			(layer "F.SilkS")
			(hide yes)
			(effects
				(font
					(size 1.27 1.27)
				)
			)
		)
		(property "Value" ""
			(at 0 0 0)
			(layer "F.Fab")
			(effects
				(font
					(size 1.27 1.27)
				)
			)
		)
		(duplicate_pad_numbers_are_jumpers no)
		(fp_poly
			(pts
				(xy -0.2794 -0.1016) (xy 0.2794 -0.1016) (xy 0.2794 0.9906) (xy -0.2794 0.9906)
			)
			(stroke
				(width 0)
				(type default)
			)
			(fill no)
			(layer "F.CrtYd")
		)
		(fp_line
			(start -0.2794 -0.1016)
			(end -0.2794 0.9906)
			(stroke
				(width 0.1)
				(type default)
			)
			(layer "F.Fab")
		)
		(fp_line
			(start -0.2794 0.9906)
			(end 0.2794 0.9906)
			(stroke
				(width 0.1)
				(type default)
			)
			(layer "F.Fab")
		)
		(fp_line
			(start 0.2794 -0.1016)
			(end -0.2794 -0.1016)
			(stroke
				(width 0.1)
				(type default)
			)
			(layer "F.Fab")
		)
		(fp_line
			(start 0.2794 0.9906)
			(end 0.2794 -0.1016)
			(stroke
				(width 0.1)
				(type default)
			)
			(layer "F.Fab")
		)
		(pad "1" smd rect
			(at 0 0)
			(size 0.508 0.508)
			(layers "F.Cu" "F.Mask" "F.Paste")
			(net "PWRGD_PVTT_DEF_CPU0_R")
		)
		(pad "2" smd rect
			(at 0 0.889)
			(size 0.508 0.508)
			(layers "F.Cu" "F.Mask" "F.Paste")
			(net "PWRGD_PVTT_CPU0")
		)
		(zone
			(layer "F.Cu")
			(hatch none 0.5)
			(connect_pads
				(clearance 0)
			)
			(min_thickness 0.25)
			(keepout
				(tracks allowed)
				(vias not_allowed)
				(pads allowed)
				(copperpour not_allowed)
				(footprints allowed)
			)
			(placement
				(enabled no)
				(sheetname "")
			)
			(fill
				(thermal_gap 0.5)
				(thermal_bridge_width 0.5)
				(island_removal_mode 0)
			)
			(polygon
				(pts
					(xy 185.1914 -146.4183) (xy 185.6994 -146.4183) (xy 185.6994 -146.0373) (xy 185.1914 -146.0373)
				)
			)
		)
		(zone
			(layer "F.Cu")
			(hatch none 0.5)
			(connect_pads
				(clearance 0)
			)
			(min_thickness 0.25)
			(keepout
				(tracks not_allowed)
				(vias allowed)
				(pads allowed)
				(copperpour not_allowed)
				(footprints allowed)
			)
			(placement
				(enabled no)
				(sheetname "")
			)
			(fill
				(thermal_gap 0.5)
				(thermal_bridge_width 0.5)
				(island_removal_mode 0)
			)
			(polygon
				(pts
					(xy 185.1914 -146.0373) (xy 185.6994 -146.0373) (xy 185.6994 -146.4183) (xy 185.1914 -146.4183)
				)
			)
		)
	)
)
